(kicad_pcb
	(version 20260206)
	(generator "pcbnew")
	(generator_version "10.0")
	(general
		(thickness 1.6)
		(legacy_teardrops no)
	)
	(paper "A4")
	(title_block
		(title "04192023_DAF0TMB3IC0_F0TG_MB_C_brd_V02_OCP.brd")
		(comment 1 "Grand Teton / footprints 7768-7774 of 8354")
	)
	(layers
		(0 "F.Cu" signal "TOP")
		(4 "In1.Cu" signal "GND")
		(6 "In2.Cu" signal "IN1")
		(8 "In3.Cu" signal "GND1")
		(10 "In4.Cu" signal "IN2")
		(12 "In5.Cu" signal "GND2")
		(14 "In6.Cu" signal "IN3")
		(16 "In7.Cu" signal "GND3")
		(18 "In8.Cu" signal "VCC")
		(20 "In9.Cu" signal "VCC1")
		(22 "In10.Cu" signal "GND4")
		(24 "In11.Cu" signal "IN4")
		(26 "In12.Cu" signal "GND5")
		(28 "In13.Cu" signal "IN5")
		(30 "In14.Cu" signal "GND6")
		(32 "In15.Cu" signal "IN6")
		(34 "In16.Cu" signal "GND7")
		(2 "B.Cu" signal "BOTTOM")
		(9 "F.Adhes" user "F.Adhesive")
		(11 "B.Adhes" user "B.Adhesive")
		(13 "F.Paste" user "Package Geometry/Pastemask Top")
		(15 "B.Paste" user "Package Geometry/Pastemask Bottom")
		(5 "F.SilkS" user "Ref Des/Silkscreen Top")
		(7 "B.SilkS" user "Ref Des/Silkscreen Bottom")
		(1 "F.Mask" user "Board Geometry/Soldermask Top")
		(3 "B.Mask" user "Board Geometry/Soldermask Bottom")
		(17 "Dwgs.User" user "User.Drawings")
		(19 "Cmts.User" user "User.Comments")
		(21 "Eco1.User" user "User.Eco1")
		(23 "Eco2.User" user "User.Eco2")
		(25 "Edge.Cuts" user "Board Geometry/Outline")
		(27 "Margin" user)
		(31 "F.CrtYd" user "Package Geometry/Place Bound Top")
		(29 "B.CrtYd" user "Package Geometry/Place Bound Bottom")
		(35 "F.Fab" user "Ref Des/Assembly Top")
		(33 "B.Fab" user "Ref Des/Assembly Bottom")
	)
	(footprint ""
		(layer "B.Cu")
		(at 376.722386 -214.523828 90)
		(property "Reference" "R8565"
			(at 0 0 90)
			(layer "B.SilkS")
			(hide yes)
			(effects
				(font
					(size 1.27 1.27)
				)
				(justify mirror)
			)
		)
		(property "Value" ""
			(at 0 0 90)
			(layer "B.Fab")
			(effects
				(font
					(size 1.27 1.27)
				)
				(justify mirror)
			)
		)
		(duplicate_pad_numbers_are_jumpers no)
		(fp_line
			(start 0.385572 -0.4064)
			(end -0.351028 -0.4064)
			(stroke
				(width 0.1524)
				(type default)
			)
			(layer "B.SilkS")
		)
		(fp_line
			(start -0.7874 0.086614)
			(end -0.7874 0.4064)
			(stroke
				(width 0.1524)
				(type default)
			)
			(layer "B.SilkS")
		)
		(fp_line
			(start 0.7874 0.4064)
			(end 0.7874 -0.014986)
			(stroke
				(width 0.1524)
				(type default)
			)
			(layer "B.SilkS")
		)
		(fp_line
			(start -0.7874 0.4064)
			(end 0.7874 0.4064)
			(stroke
				(width 0.1524)
				(type default)
			)
			(layer "B.SilkS")
		)
		(fp_line
			(start 0.67945 -0.305054)
			(end 0.12065 -0.305054)
			(stroke
				(width 0.1)
				(type default)
			)
			(layer "B.Fab")
		)
		(fp_line
			(start 0.12065 -0.305054)
			(end 0.12065 -0.2794)
			(stroke
				(width 0.1)
				(type default)
			)
			(layer "B.Fab")
		)
		(fp_line
			(start -0.12065 -0.3048)
			(end -0.67945 -0.3048)
			(stroke
				(width 0.1)
				(type default)
			)
			(layer "B.Fab")
		)
		(fp_line
			(start -0.67945 -0.3048)
			(end -0.67945 0.3048)
			(stroke
				(width 0.1)
				(type default)
			)
			(layer "B.Fab")
		)
		(fp_line
			(start 0.12065 -0.2794)
			(end -0.12065 -0.2794)
			(stroke
				(width 0.1)
				(type default)
			)
			(layer "B.Fab")
		)
		(fp_line
			(start -0.12065 -0.2794)
			(end -0.12065 -0.3048)
			(stroke
				(width 0.1)
				(type default)
			)
			(layer "B.Fab")
		)
		(fp_line
			(start 0.12065 0.2794)
			(end 0.12065 0.3048)
			(stroke
				(width 0.1)
				(type default)
			)
			(layer "B.Fab")
		)
		(fp_line
			(start -0.120396 0.2794)
			(end 0.12065 0.2794)
			(stroke
				(width 0.1)
				(type default)
			)
			(layer "B.Fab")
		)
		(fp_line
			(start 0.67945 0.3048)
			(end 0.67945 -0.305054)
			(stroke
				(width 0.1)
				(type default)
			)
			(layer "B.Fab")
		)
		(fp_line
			(start 0.12065 0.3048)
			(end 0.67945 0.3048)
			(stroke
				(width 0.1)
				(type default)
			)
			(layer "B.Fab")
		)
		(fp_line
			(start -0.120396 0.3048)
			(end -0.120396 0.2794)
			(stroke
				(width 0.1)
				(type default)
			)
			(layer "B.Fab")
		)
		(fp_line
			(start -0.67945 0.3048)
			(end -0.120396 0.3048)
			(stroke
				(width 0.1)
				(type default)
			)
			(layer "B.Fab")
		)
		(pad "1" smd circle
			(at 0.40005 0 270)
			(size 0 0)
			(layers "B.Cu" "B.Mask" "B.Paste")
			(net "CLK_100M_CPU0_CLK03_R_DP")
		)
		(pad "2" smd circle
			(at -0.40005 0 270)
			(size 0 0)
			(layers "B.Cu" "B.Mask" "B.Paste")
			(net "CLK_100M_CPU0_CLK03_DP")
		)
	)
	(footprint ""
		(layer "B.Cu")
		(at 414.085786 -151.33701 90)
		(property "Reference" "PC1855"
			(at 0 0 90)
			(layer "B.SilkS")
			(hide yes)
			(effects
				(font
					(size 1.27 1.27)
				)
				(justify mirror)
			)
		)
		(property "Value" ""
			(at 0 0 90)
			(layer "B.Fab")
			(effects
				(font
					(size 1.27 1.27)
				)
				(justify mirror)
			)
		)
		(duplicate_pad_numbers_are_jumpers no)
		(fp_line
			(start 1.524 -0.762)
			(end -1.524 -0.762)
			(stroke
				(width 0.1524)
				(type default)
			)
			(layer "B.SilkS")
		)
		(fp_line
			(start -1.524 -0.762)
			(end -1.524 0.762)
			(stroke
				(width 0.1524)
				(type default)
			)
			(layer "B.SilkS")
		)
		(fp_line
			(start 1.524 0.762)
			(end 1.524 -0.762)
			(stroke
				(width 0.1524)
				(type default)
			)
			(layer "B.SilkS")
		)
		(fp_line
			(start -1.524 0.762)
			(end 1.524 0.762)
			(stroke
				(width 0.1524)
				(type default)
			)
			(layer "B.SilkS")
		)
		(fp_line
			(start 1.1049 -0.724916)
			(end 1.1049 0.724916)
			(stroke
				(width 0.1)
				(type default)
			)
			(layer "B.Fab")
		)
		(fp_line
			(start -1.1049 -0.724916)
			(end 1.1049 -0.724916)
			(stroke
				(width 0.1)
				(type default)
			)
			(layer "B.Fab")
		)
		(fp_line
			(start 1.1049 0.724916)
			(end -1.1049 0.724916)
			(stroke
				(width 0.1)
				(type default)
			)
			(layer "B.Fab")
		)
		(fp_line
			(start -1.1049 0.724916)
			(end -1.1049 -0.724916)
			(stroke
				(width 0.1)
				(type default)
			)
			(layer "B.Fab")
		)
		(pad "1" smd rect
			(at 0.889 0 90)
			(size 1.016 1.27)
			(layers "B.Cu" "B.Mask" "B.Paste")
			(net "P5V_AUX")
		)
		(pad "2" smd rect
			(at -0.889 0 90)
			(size 1.016 1.27)
			(layers "B.Cu" "B.Mask" "B.Paste")
			(net "GND")
		)
	)
	(footprint ""
		(layer "B.Cu")
		(at 131.418584 -388.011162 -90)
		(property "Reference" "C462"
			(at 0 0 90)
			(layer "B.SilkS")
			(hide yes)
			(effects
				(font
					(size 1.27 1.27)
				)
				(justify mirror)
			)
		)
		(property "Value" ""
			(at 0 0 90)
			(layer "B.Fab")
			(effects
				(font
					(size 1.27 1.27)
				)
				(justify mirror)
			)
		)
		(duplicate_pad_numbers_are_jumpers no)
		(fp_line
			(start -0.299974 0.150114)
			(end 0.299974 0.150114)
			(stroke
				(width 0.1)
				(type default)
			)
			(layer "B.Fab")
		)
		(fp_line
			(start 0.299974 0.150114)
			(end 0.299974 -0.150114)
			(stroke
				(width 0.1)
				(type default)
			)
			(layer "B.Fab")
		)
		(fp_line
			(start -0.299974 -0.150114)
			(end -0.299974 0.150114)
			(stroke
				(width 0.1)
				(type default)
			)
			(layer "B.Fab")
		)
		(fp_line
			(start 0.299974 -0.150114)
			(end -0.299974 -0.150114)
			(stroke
				(width 0.1)
				(type default)
			)
			(layer "B.Fab")
		)
		(pad "1" smd rect
			(at 0.2667 0 90)
			(size 0.3048 0.381)
			(layers "B.Cu" "B.Mask" "B.Paste")
			(net "P0V9_CPU1_RT3_2A")
		)
		(pad "2" smd rect
			(at -0.2667 0 90)
			(size 0.3048 0.381)
			(layers "B.Cu" "B.Mask" "B.Paste")
			(net "GND")
		)
	)
	(footprint ""
		(layer "B.Cu")
		(at 411.576266 -139.42949 90)
		(property "Reference" "R2356"
			(at 0 0 90)
			(layer "B.SilkS")
			(hide yes)
			(effects
				(font
					(size 1.27 1.27)
				)
				(justify mirror)
			)
		)
		(property "Value" ""
			(at 0 0 90)
			(layer "B.Fab")
			(effects
				(font
					(size 1.27 1.27)
				)
				(justify mirror)
			)
		)
		(duplicate_pad_numbers_are_jumpers no)
		(fp_line
			(start 0.7874 -0.4064)
			(end -0.7874 -0.4064)
			(stroke
				(width 0.1524)
				(type default)
			)
			(layer "B.SilkS")
		)
		(fp_line
			(start -0.7874 -0.4064)
			(end -0.7874 0.4064)
			(stroke
				(width 0.1524)
				(type default)
			)
			(layer "B.SilkS")
		)
		(fp_line
			(start 0.7874 0.4064)
			(end 0.7874 -0.4064)
			(stroke
				(width 0.1524)
				(type default)
			)
			(layer "B.SilkS")
		)
		(fp_line
			(start -0.7874 0.4064)
			(end 0.7874 0.4064)
			(stroke
				(width 0.1524)
				(type default)
			)
			(layer "B.SilkS")
		)
		(fp_line
			(start 0.67945 -0.305054)
			(end 0.12065 -0.305054)
			(stroke
				(width 0.1)
				(type default)
			)
			(layer "B.Fab")
		)
		(fp_line
			(start 0.12065 -0.305054)
			(end 0.12065 -0.2794)
			(stroke
				(width 0.1)
				(type default)
			)
			(layer "B.Fab")
		)
		(fp_line
			(start -0.12065 -0.3048)
			(end -0.67945 -0.3048)
			(stroke
				(width 0.1)
				(type default)
			)
			(layer "B.Fab")
		)
		(fp_line
			(start -0.67945 -0.3048)
			(end -0.67945 0.3048)
			(stroke
				(width 0.1)
				(type default)
			)
			(layer "B.Fab")
		)
		(fp_line
			(start 0.12065 -0.2794)
			(end -0.12065 -0.2794)
			(stroke
				(width 0.1)
				(type default)
			)
			(layer "B.Fab")
		)
		(fp_line
			(start -0.12065 -0.2794)
			(end -0.12065 -0.3048)
			(stroke
				(width 0.1)
				(type default)
			)
			(layer "B.Fab")
		)
		(fp_line
			(start 0.12065 0.2794)
			(end 0.12065 0.3048)
			(stroke
				(width 0.1)
				(type default)
			)
			(layer "B.Fab")
		)
		(fp_line
			(start -0.120396 0.2794)
			(end 0.12065 0.2794)
			(stroke
				(width 0.1)
				(type default)
			)
			(layer "B.Fab")
		)
		(fp_line
			(start 0.67945 0.3048)
			(end 0.67945 -0.305054)
			(stroke
				(width 0.1)
				(type default)
			)
			(layer "B.Fab")
		)
		(fp_line
			(start 0.12065 0.3048)
			(end 0.67945 0.3048)
			(stroke
				(width 0.1)
				(type default)
			)
			(layer "B.Fab")
		)
		(fp_line
			(start -0.120396 0.3048)
			(end -0.120396 0.2794)
			(stroke
				(width 0.1)
				(type default)
			)
			(layer "B.Fab")
		)
		(fp_line
			(start -0.67945 0.3048)
			(end -0.120396 0.3048)
			(stroke
				(width 0.1)
				(type default)
			)
			(layer "B.Fab")
		)
		(pad "1" smd circle
			(at 0.40005 0 270)
			(size 0 0)
			(layers "B.Cu" "B.Mask" "B.Paste")
			(net "P5V_AUX_VCC")
		)
		(pad "2" smd circle
			(at -0.40005 0 270)
			(size 0 0)
			(layers "B.Cu" "B.Mask" "B.Paste")
			(net "PWRGD_P5V_AUX_R")
		)
	)
	(footprint ""
		(layer "B.Cu")
		(at 85.024976 -381.11303 180)
		(property "Reference" "C7024"
			(at -1.773428 -2.989072 0)
			(unlocked yes)
			(layer "B.SilkS")
			(effects
				(font
					(size 0.7874 0.5842)
					(thickness 0.1524)
				)
				(justify left mirror)
			)
		)
		(property "Value" ""
			(at 0 0 0)
			(layer "B.Fab")
			(effects
				(font
					(size 1.27 1.27)
				)
				(justify mirror)
			)
		)
		(duplicate_pad_numbers_are_jumpers no)
		(fp_line
			(start 4.84378 -2.150618)
			(end 4.842256 2.163064)
			(stroke
				(width 0.1524)
				(type default)
			)
			(layer "B.SilkS")
		)
		(fp_line
			(start 4.84378 -2.150618)
			(end 4.53898 -2.150618)
			(stroke
				(width 0.1524)
				(type default)
			)
			(layer "B.SilkS")
		)
		(fp_line
			(start 4.83108 2.150364)
			(end 4.447794 2.149348)
			(stroke
				(width 0.1524)
				(type default)
			)
			(layer "B.SilkS")
		)
		(fp_line
			(start 4.69138 -2.150618)
			(end 4.692396 2.161032)
			(stroke
				(width 0.1524)
				(type default)
			)
			(layer "B.SilkS")
		)
		(fp_line
			(start 4.53898 2.15011)
			(end 4.53898 -2.15011)
			(stroke
				(width 0.1524)
				(type default)
			)
			(layer "B.SilkS")
		)
		(fp_line
			(start 4.53898 -2.15011)
			(end -4.53898 -2.15011)
			(stroke
				(width 0.1524)
				(type default)
			)
			(layer "B.SilkS")
		)
		(fp_line
			(start 4.53898 -2.150618)
			(end 4.539742 2.152142)
			(stroke
				(width 0.1524)
				(type default)
			)
			(layer "B.SilkS")
		)
		(fp_line
			(start -4.53898 2.15011)
			(end 4.53898 2.15011)
			(stroke
				(width 0.1524)
				(type default)
			)
			(layer "B.SilkS")
		)
		(fp_line
			(start -4.53898 -2.15011)
			(end -4.53898 2.15011)
			(stroke
				(width 0.1524)
				(type default)
			)
			(layer "B.SilkS")
		)
		(fp_line
			(start 3.64998 2.15011)
			(end 3.64998 -2.15011)
			(stroke
				(width 0.1)
				(type default)
			)
			(layer "B.Fab")
		)
		(fp_line
			(start 3.64998 -2.15011)
			(end -3.64998 -2.15011)
			(stroke
				(width 0.1)
				(type default)
			)
			(layer "B.Fab")
		)
		(fp_line
			(start -3.64998 2.15011)
			(end 3.64998 2.15011)
			(stroke
				(width 0.1)
				(type default)
			)
			(layer "B.Fab")
		)
		(fp_line
			(start -3.64998 -2.15011)
			(end -3.64998 2.15011)
			(stroke
				(width 0.1)
				(type default)
			)
			(layer "B.Fab")
		)
		(fp_text user "+"
			(at 4.256532 -3.098038 180)
			(unlocked yes)
			(layer "B.SilkS")
			(effects
				(font
					(size 1.905 1.4224)
					(thickness 0.1524)
				)
				(justify left mirror)
			)
		)
		(fp_text user "-"
			(at -2.946654 -2.901188 180)
			(unlocked yes)
			(layer "B.SilkS")
			(effects
				(font
					(size 1.905 1.4224)
					(thickness 0.1524)
				)
				(justify left mirror)
			)
		)
		(fp_text user "+"
			(at 6.214872 -0.337058 180)
			(unlocked yes)
			(layer "B.Fab")
			(effects
				(font
					(size 1.905 1.4224)
					(thickness 0.1524)
				)
				(justify left mirror)
			)
		)
		(fp_text user "-"
			(at -4.313174 -0.094488 180)
			(unlocked yes)
			(layer "B.Fab")
			(effects
				(font
					(size 1.905 1.4224)
					(thickness 0.1524)
				)
				(justify left mirror)
			)
		)
		(pad "1" smd rect
			(at 3.199892 0)
			(size 2.413 2.8194)
			(layers "B.Cu" "B.Mask" "B.Paste")
			(net "P0V9_CPU1_RT1_2A")
		)
		(pad "2" smd rect
			(at -3.199892 0)
			(size 2.413 2.8194)
			(layers "B.Cu" "B.Mask" "B.Paste")
			(net "GND")
		)
	)
	(footprint ""
		(layer "B.Cu")
		(at 429.659796 -352.199448 -90)
		(property "Reference" "PR132"
			(at 0 0 90)
			(layer "B.SilkS")
			(hide yes)
			(effects
				(font
					(size 1.27 1.27)
				)
				(justify mirror)
			)
		)
		(property "Value" ""
			(at 0 0 90)
			(layer "B.Fab")
			(effects
				(font
					(size 1.27 1.27)
				)
				(justify mirror)
			)
		)
		(duplicate_pad_numbers_are_jumpers no)
		(fp_line
			(start -0.7874 0.4064)
			(end 0.7874 0.4064)
			(stroke
				(width 0.1524)
				(type default)
			)
			(layer "B.SilkS")
		)
		(fp_line
			(start 0.7874 0.4064)
			(end 0.7874 -0.4064)
			(stroke
				(width 0.1524)
				(type default)
			)
			(layer "B.SilkS")
		)
		(fp_line
			(start -0.7874 -0.4064)
			(end -0.7874 0.4064)
			(stroke
				(width 0.1524)
				(type default)
			)
			(layer "B.SilkS")
		)
		(fp_line
			(start 0.7874 -0.4064)
			(end -0.7874 -0.4064)
			(stroke
				(width 0.1524)
				(type default)
			)
			(layer "B.SilkS")
		)
		(fp_line
			(start -0.67945 0.3048)
			(end -0.120396 0.3048)
			(stroke
				(width 0.1)
				(type default)
			)
			(layer "B.Fab")
		)
		(fp_line
			(start -0.120396 0.3048)
			(end -0.120396 0.2794)
			(stroke
				(width 0.1)
				(type default)
			)
			(layer "B.Fab")
		)
		(fp_line
			(start 0.12065 0.3048)
			(end 0.67945 0.3048)
			(stroke
				(width 0.1)
				(type default)
			)
			(layer "B.Fab")
		)
		(fp_line
			(start 0.67945 0.3048)
			(end 0.67945 -0.305054)
			(stroke
				(width 0.1)
				(type default)
			)
			(layer "B.Fab")
		)
		(fp_line
			(start -0.120396 0.2794)
			(end 0.12065 0.2794)
			(stroke
				(width 0.1)
				(type default)
			)
			(layer "B.Fab")
		)
		(fp_line
			(start 0.12065 0.2794)
			(end 0.12065 0.3048)
			(stroke
				(width 0.1)
				(type default)
			)
			(layer "B.Fab")
		)
		(fp_line
			(start -0.12065 -0.2794)
			(end -0.12065 -0.3048)
			(stroke
				(width 0.1)
				(type default)
			)
			(layer "B.Fab")
		)
		(fp_line
			(start 0.12065 -0.2794)
			(end -0.12065 -0.2794)
			(stroke
				(width 0.1)
				(type default)
			)
			(layer "B.Fab")
		)
		(fp_line
			(start -0.67945 -0.3048)
			(end -0.67945 0.3048)
			(stroke
				(width 0.1)
				(type default)
			)
			(layer "B.Fab")
		)
		(fp_line
			(start -0.12065 -0.3048)
			(end -0.67945 -0.3048)
			(stroke
				(width 0.1)
				(type default)
			)
			(layer "B.Fab")
		)
		(fp_line
			(start 0.12065 -0.305054)
			(end 0.12065 -0.2794)
			(stroke
				(width 0.1)
				(type default)
			)
			(layer "B.Fab")
		)
		(fp_line
			(start 0.67945 -0.305054)
			(end 0.12065 -0.305054)
			(stroke
				(width 0.1)
				(type default)
			)
			(layer "B.Fab")
		)
		(pad "1" smd circle
			(at 0.40005 0 90)
			(size 0 0)
			(layers "B.Cu" "B.Mask" "B.Paste")
			(net "PVDD11_S3_P0_PVCC")
		)
		(pad "2" smd circle
			(at -0.40005 0 90)
			(size 0 0)
			(layers "B.Cu" "B.Mask" "B.Paste")
			(net "PVDD11_S3_P0_VCC2")
		)
	)
	(footprint ""
		(layer "B.Cu")
		(at 115.130834 -246.376952 180)
		(property "Reference" "C2324"
			(at 0 0 0)
			(layer "B.SilkS")
			(hide yes)
			(effects
				(font
					(size 1.27 1.27)
				)
				(justify mirror)
			)
		)
		(property "Value" ""
			(at 0 0 0)
			(layer "B.Fab")
			(effects
				(font
					(size 1.27 1.27)
				)
				(justify mirror)
			)
		)
		(duplicate_pad_numbers_are_jumpers no)
		(fp_line
			(start 0.7874 0.4064)
			(end 0.7874 -0.4064)
			(stroke
				(width 0.1524)
				(type default)
			)
			(layer "B.SilkS")
		)
		(fp_line
			(start 0.7874 -0.4064)
			(end -0.7874 -0.4064)
			(stroke
				(width 0.1524)
				(type default)
			)
			(layer "B.SilkS")
		)
		(fp_line
			(start -0.7874 0.4064)
			(end 0.7874 0.4064)
			(stroke
				(width 0.1524)
				(type default)
			)
			(layer "B.SilkS")
		)
		(fp_line
			(start -0.7874 -0.4064)
			(end -0.7874 0.4064)
			(stroke
				(width 0.1524)
				(type default)
			)
			(layer "B.SilkS")
		)
		(fp_line
			(start 0.67945 0.3048)
			(end 0.67945 -0.305054)
			(stroke
				(width 0.1)
				(type default)
			)
			(layer "B.Fab")
		)
		(fp_line
			(start 0.67945 -0.305054)
			(end 0.12065 -0.305054)
			(stroke
				(width 0.1)
				(type default)
			)
			(layer "B.Fab")
		)
		(fp_line
			(start 0.12065 0.3048)
			(end 0.67945 0.3048)
			(stroke
				(width 0.1)
				(type default)
			)
			(layer "B.Fab")
		)
		(fp_line
			(start 0.12065 0.2794)
			(end 0.12065 0.3048)
			(stroke
				(width 0.1)
				(type default)
			)
			(layer "B.Fab")
		)
		(fp_line
			(start 0.12065 -0.2794)
			(end -0.12065 -0.2794)
			(stroke
				(width 0.1)
				(type default)
			)
			(layer "B.Fab")
		)
		(fp_line
			(start 0.12065 -0.305054)
			(end 0.12065 -0.2794)
			(stroke
				(width 0.1)
				(type default)
			)
			(layer "B.Fab")
		)
		(fp_line
			(start -0.120396 0.3048)
			(end -0.120396 0.2794)
			(stroke
				(width 0.1)
				(type default)
			)
			(layer "B.Fab")
		)
		(fp_line
			(start -0.120396 0.2794)
			(end 0.12065 0.2794)
			(stroke
				(width 0.1)
				(type default)
			)
			(layer "B.Fab")
		)
		(fp_line
			(start -0.12065 -0.2794)
			(end -0.12065 -0.3048)
			(stroke
				(width 0.1)
				(type default)
			)
			(layer "B.Fab")
		)
		(fp_line
			(start -0.12065 -0.3048)
			(end -0.67945 -0.3048)
			(stroke
				(width 0.1)
				(type default)
			)
			(layer "B.Fab")
		)
		(fp_line
			(start -0.67945 0.3048)
			(end -0.120396 0.3048)
			(stroke
				(width 0.1)
				(type default)
			)
			(layer "B.Fab")
		)
		(fp_line
			(start -0.67945 -0.3048)
			(end -0.67945 0.3048)
			(stroke
				(width 0.1)
				(type default)
			)
			(layer "B.Fab")
		)
		(pad "1" smd circle
			(at 0.40005 0)
			(size 0 0)
			(layers "B.Cu" "B.Mask" "B.Paste")
			(net "PVDDCR_CPU0_P1")
		)
		(pad "2" smd circle
			(at -0.40005 0)
			(size 0 0)
			(layers "B.Cu" "B.Mask" "B.Paste")
			(net "GND")
		)
	)
)
